# TIMECARD (Time Appliance Project (Time Card)) — schematic netlist excerpt (pin names and nets, part order shuffled) for the footprints in the layout excerpt that follows; sources: Cadence DE-HDL packaged netlist, KiCad conversion of R4006-B0001-02_R01.brd

C191  CAPACITOR  0.01UF 25V 10%  pkg SMC_0201R  page 30 : \1\ = XP1R8V_SS ; \2\ = SG
R157  RESISTOR  100OHM 1%  pkg SMC_0402R_H016  page 23 : \1\ = ANT4_OUT ; \2\ = UNNAMED_12_74HCT2G125DPTSSOP8_3

(kicad_pcb
	(version 20260206)
	(generator "pcbnew")
	(generator_version "10.0")
	(general
		(thickness 1.6)
		(legacy_teardrops no)
	)
	(paper "A4")
	(title_block
		(title "timecard-production-celestica-r4006 — R4006-B0001-02_R01.brd")
		(comment 1 "Time Appliance Project (Time Card) / footprints 466-467 of 1113")
	)
	(layers
		(0 "F.Cu" signal "TOP")
		(4 "In1.Cu" signal "L02_GND1")
		(6 "In2.Cu" signal "L03_SIG1")
		(8 "In3.Cu" signal "L04_GND2")
		(10 "In4.Cu" signal "L05_VCC1")
		(12 "In5.Cu" signal "L06_VCC2")
		(14 "In6.Cu" signal "L07_GND3")
		(16 "In7.Cu" signal "L08_SIG2")
		(18 "In8.Cu" signal "L09_GND4")
		(2 "B.Cu" signal "BOTTOM")
		(9 "F.Adhes" user "F.Adhesive")
		(11 "B.Adhes" user "B.Adhesive")
		(13 "F.Paste" user "Package Geometry/Pastemask Top")
		(15 "B.Paste" user "Package Geometry/Pastemask Bottom")
		(5 "F.SilkS" user "Ref Des/Silkscreen Top")
		(7 "B.SilkS" user "Ref Des/Silkscreen Bottom")
		(1 "F.Mask" user "Board Geometry/Soldermask Top")
		(3 "B.Mask" user "Board Geometry/Soldermask Bottom")
		(17 "Dwgs.User" user "User.Drawings")
		(19 "Cmts.User" user "User.Comments")
		(21 "Eco1.User" user "User.Eco1")
		(23 "Eco2.User" user "User.Eco2")
		(25 "Edge.Cuts" user "Board Geometry/Outline")
		(27 "Margin" user)
		(31 "F.CrtYd" user "Package Geometry/Place Bound Top")
		(29 "B.CrtYd" user "Package Geometry/Place Bound Bottom")
		(35 "F.Fab" user "Ref Des/Assembly Top")
		(33 "B.Fab" user "Ref Des/Assembly Bottom")
	)
	(footprint ""
		(layer "F.Cu")
		(at 126.0602 -70.5358 180)
		(property "Reference" "C191"
			(at 0.0762 3.33883 0)
			(unlocked yes)
			(layer "F.SilkS")
			(effects
				(font
					(size 0.7874 0.5842)
					(thickness 0.1524)
				)
			)
		)
		(property "Value" "VAL*"
			(at 0.193548 2.13614 180)
			(unlocked yes)
			(layer "F.Fab")
			(hide yes)
			(effects
				(font
					(size 0.7874 0.5842)
					(thickness 0.1524)
				)
			)
		)
		(property "Tolerance" "TOL*"
			(at 0.216154 3.1496 180)
			(unlocked yes)
			(layer "Cmts.User")
			(hide yes)
			(effects
				(font
					(size 0.7874 0.5842)
					(thickness 0.1524)
				)
			)
		)
		(property "Device Type" "CAPACITOR-G104-0B103-EK,0.01UFA"
			(at 0.184404 1.180592 180)
			(unlocked yes)
			(layer "F.Fab")
			(hide yes)
			(effects
				(font
					(size 0.7874 0.5842)
					(thickness 0.1524)
				)
			)
		)
		(property "User Part Number" "PARTNUM*"
			(at 0.216154 4.185666 180)
			(unlocked yes)
			(layer "Cmts.User")
			(hide yes)
			(effects
				(font
					(size 0.7874 0.5842)
					(thickness 0.1524)
				)
			)
		)
		(duplicate_pad_numbers_are_jumpers no)
		(fp_line
			(start 0.671322 0.4445)
			(end -0.671322 0.4445)
			(stroke
				(width 0.1)
				(type default)
			)
			(layer "F.SilkS")
		)
		(fp_line
			(start 0.671322 -0.4445)
			(end 0.671322 0.4445)
			(stroke
				(width 0.1)
				(type default)
			)
			(layer "F.SilkS")
		)
		(fp_line
			(start -0.671322 0.4445)
			(end -0.671322 -0.4445)
			(stroke
				(width 0.1)
				(type default)
			)
			(layer "F.SilkS")
		)
		(fp_line
			(start -0.671322 -0.4445)
			(end 0.671322 -0.4445)
			(stroke
				(width 0.1)
				(type default)
			)
			(layer "F.SilkS")
		)
		(fp_rect
			(start -0.671322 0.4445)
			(end 0.671322 -0.4445)
			(stroke
				(width 0)
				(type default)
			)
			(fill no)
			(layer "F.CrtYd")
		)
		(fp_line
			(start 0.31496 0.1651)
			(end 0.31496 -0.1651)
			(stroke
				(width 0.1)
				(type default)
			)
			(layer "F.Fab")
		)
		(fp_line
			(start 0.31496 -0.1651)
			(end -0.31496 -0.1651)
			(stroke
				(width 0.1)
				(type default)
			)
			(layer "F.Fab")
		)
		(fp_line
			(start -0.31496 0.1651)
			(end 0.31496 0.1651)
			(stroke
				(width 0.1)
				(type default)
			)
			(layer "F.Fab")
		)
		(fp_line
			(start -0.31496 -0.1651)
			(end -0.31496 0.1651)
			(stroke
				(width 0.1)
				(type default)
			)
			(layer "F.Fab")
		)
		(pad "1" smd rect
			(at -0.264922 0 180)
			(size 0.3048 0.381)
			(layers "F.Cu" "F.Mask" "F.Paste")
			(net "XP1R8V_SS")
		)
		(pad "2" smd rect
			(at 0.264922 0 180)
			(size 0.3048 0.381)
			(layers "F.Cu" "F.Mask" "F.Paste")
			(net "SG")
		)
		(zone
			(layer "F.Cu")
			(hatch none 0.5)
			(connect_pads
				(clearance 0)
			)
			(min_thickness 0.25)
			(keepout
				(tracks allowed)
				(vias not_allowed)
				(pads allowed)
				(copperpour not_allowed)
				(footprints allowed)
			)
			(placement
				(enabled no)
				(sheetname "")
			)
			(fill
				(thermal_gap 0.5)
				(thermal_bridge_width 0.5)
				(island_removal_mode 0)
			)
			(polygon
				(pts
					(xy 126.172722 -70.7263) (xy 125.947678 -70.7263) (xy 125.947678 -70.3453) (xy 126.172722 -70.3453)
				)
			)
		)
	)
	(footprint ""
		(layer "F.Cu")
		(at 13.589 -22.987 -90)
		(property "Reference" "R157"
			(at 0.635 3.51663 90)
			(unlocked yes)
			(layer "F.SilkS")
			(effects
				(font
					(size 0.7874 0.5842)
					(thickness 0.1524)
				)
			)
		)
		(property "Value" "VAL*"
			(at 0.02032 2.13233 270)
			(unlocked yes)
			(layer "F.Fab")
			(hide yes)
			(effects
				(font
					(size 0.7874 0.5842)
					(thickness 0.1524)
				)
			)
		)
		(property "Tolerance" "TOL*"
			(at 0.044704 3.05435 270)
			(unlocked yes)
			(layer "Cmts.User")
			(hide yes)
			(effects
				(font
					(size 0.7874 0.5842)
					(thickness 0.1524)
				)
			)
		)
		(property "User Part Number" "PARTNUM*"
			(at 0.02032 4.024884 270)
			(unlocked yes)
			(layer "Cmts.User")
			(hide yes)
			(effects
				(font
					(size 0.7874 0.5842)
					(thickness 0.1524)
				)
			)
		)
		(property "Device Type" "RESISTOR-G155-11000-01,100OHM,A"
			(at 0.008382 1.210564 270)
			(unlocked yes)
			(layer "F.Fab")
			(hide yes)
			(effects
				(font
					(size 0.7874 0.5842)
					(thickness 0.1524)
				)
			)
		)
		(duplicate_pad_numbers_are_jumpers no)
		(fp_line
			(start -1.143 0.5588)
			(end 1.143 0.5588)
			(stroke
				(width 0.1)
				(type default)
			)
			(layer "F.SilkS")
		)
		(fp_line
			(start 1.143 0.5588)
			(end 1.143 -0.5588)
			(stroke
				(width 0.1)
				(type default)
			)
			(layer "F.SilkS")
		)
		(fp_line
			(start -1.143 -0.5588)
			(end -1.143 0.5588)
			(stroke
				(width 0.1)
				(type default)
			)
			(layer "F.SilkS")
		)
		(fp_line
			(start 1.143 -0.5588)
			(end -1.143 -0.5588)
			(stroke
				(width 0.1)
				(type default)
			)
			(layer "F.SilkS")
		)
		(fp_poly
			(pts
				(xy -1.143 0.5588) (xy 1.143 0.5588) (xy 1.143 -0.5588) (xy -1.143 -0.5588)
			)
			(stroke
				(width 0)
				(type default)
			)
			(fill no)
			(layer "F.CrtYd")
		)
		(fp_line
			(start -0.508 0.3048)
			(end 0.508 0.3048)
			(stroke
				(width 0.1)
				(type default)
			)
			(layer "F.Fab")
		)
		(fp_line
			(start 0.508 0.3048)
			(end 0.508 -0.3048)
			(stroke
				(width 0.1)
				(type default)
			)
			(layer "F.Fab")
		)
		(fp_line
			(start -0.508 -0.3048)
			(end -0.508 0.3048)
			(stroke
				(width 0.1)
				(type default)
			)
			(layer "F.Fab")
		)
		(fp_line
			(start 0.508 -0.3048)
			(end -0.508 -0.3048)
			(stroke
				(width 0.1)
				(type default)
			)
			(layer "F.Fab")
		)
		(pad "1" smd rect
			(at -0.5334 0 270)
			(size 0.7112 0.6096)
			(layers "F.Cu" "F.Mask" "F.Paste")
			(net "ANT4_OUT")
		)
		(pad "2" smd rect
			(at 0.5334 0 270)
			(size 0.7112 0.6096)
			(layers "F.Cu" "F.Mask" "F.Paste")
			(net "UNNAMED_12_74HCT2G125DPTSSOP8_3")
		)
		(zone
			(layer "F.Cu")
			(hatch none 0.5)
			(connect_pads
				(clearance 0)
			)
			(min_thickness 0.25)
			(keepout
				(tracks not_allowed)
				(vias allowed)
				(pads allowed)
				(copperpour not_allowed)
				(footprints allowed)
			)
			(placement
				(enabled no)
				(sheetname "")
			)
			(fill
				(thermal_gap 0.5)
				(thermal_bridge_width 0.5)
				(island_removal_mode 0)
			)
			(polygon
				(pts
					(xy 13.2842 -23.0632) (xy 13.2842 -22.9108) (xy 13.8938 -22.9108) (xy 13.8938 -23.0632)
				)
			)
		)
		(zone
			(layer "F.Cu")
			(hatch none 0.5)
			(connect_pads
				(clearance 0)
			)
			(min_thickness 0.25)
			(keepout
				(tracks allowed)
				(vias not_allowed)
				(pads allowed)
				(copperpour not_allowed)
				(footprints allowed)
			)
			(placement
				(enabled no)
				(sheetname "")
			)
			(fill
				(thermal_gap 0.5)
				(thermal_bridge_width 0.5)
				(island_removal_mode 0)
			)
			(polygon
				(pts
					(xy 13.2842 -23.0632) (xy 13.2842 -22.9108) (xy 13.8938 -22.9108) (xy 13.8938 -23.0632)
				)
			)
		)
	)
)
